(kicad_pcb
	(version 20260206)
	(generator "pcbnew")
	(generator_version "10.0")
	(general
		(thickness 1.6)
		(legacy_teardrops no)
	)
	(paper "A4")
	(title_block
		(title "03242023_DA0F0TMBIJ0_F0T_Motherboard_J_brd_V01_OCP.brd")
		(comment 1 "Grand Teton / footprint 461 of 6105 (J9), pads 225-291 of 291")
	)
	(layers
		(0 "F.Cu" signal "TOP")
		(4 "In1.Cu" signal "GND")
		(6 "In2.Cu" signal "IN1")
		(8 "In3.Cu" signal "GND1")
		(10 "In4.Cu" signal "IN2")
		(12 "In5.Cu" signal "GND2")
		(14 "In6.Cu" signal "IN3")
		(16 "In7.Cu" signal "GND3")
		(18 "In8.Cu" signal "VCC")
		(20 "In9.Cu" signal "VCC1")
		(22 "In10.Cu" signal "GND4")
		(24 "In11.Cu" signal "IN4")
		(26 "In12.Cu" signal "GND5")
		(28 "In13.Cu" signal "IN5")
		(30 "In14.Cu" signal "GND6")
		(32 "In15.Cu" signal "IN6")
		(34 "In16.Cu" signal "GND7")
		(2 "B.Cu" signal "BOTTOM")
		(9 "F.Adhes" user "F.Adhesive")
		(11 "B.Adhes" user "B.Adhesive")
		(13 "F.Paste" user "Package Geometry/Pastemask Top")
		(15 "B.Paste" user "Package Geometry/Pastemask Bottom")
		(5 "F.SilkS" user "Ref Des/Silkscreen Top")
		(7 "B.SilkS" user "Ref Des/Silkscreen Bottom")
		(1 "F.Mask" user "Board Geometry/Soldermask Top")
		(3 "B.Mask" user "Board Geometry/Soldermask Bottom")
		(17 "Dwgs.User" user "User.Drawings")
		(19 "Cmts.User" user "User.Comments")
		(21 "Eco1.User" user "User.Eco1")
		(23 "Eco2.User" user "User.Eco2")
		(25 "Edge.Cuts" user "Board Geometry/Outline")
		(27 "Margin" user)
		(31 "F.CrtYd" user "Package Geometry/Place Bound Top")
		(29 "B.CrtYd" user "Package Geometry/Place Bound Bottom")
		(35 "F.Fab" user "Ref Des/Assembly Top")
		(33 "B.Fab" user "Ref Des/Assembly Bottom")
	)
	(footprint ""
		(layer "F.Cu")
		(at 416.347148 -258.091686)
		(property "Reference" "J9"
			(at -3.683 -81.702148 0)
			(unlocked yes)
			(layer "F.SilkS")
			(effects
				(font
					(size 0.7874 0.5842)
					(thickness 0.1524)
				)
				(justify left)
			)
		)
		(property "Value" ""
			(at 0 0 0)
			(layer "F.Fab")
			(effects
				(font
					(size 1.27 1.27)
				)
			)
		)
		(duplicate_pad_numbers_are_jumpers no)
		(pad "225" smd rect
			(at 2.050034 9.774936 270)
			(size 0.519938 1.4986)
			(layers "F.Cu" "F.Mask" "F.Paste")
			(net "M_E_CPU0_SB_CA<5>")
		)
		(pad "226" smd rect
			(at 2.050034 10.625074 270)
			(size 0.519938 1.4986)
			(layers "F.Cu" "F.Mask" "F.Paste")
			(net "GND")
		)
		(pad "227" smd rect
			(at 2.050034 11.474958 270)
			(size 0.519938 1.4986)
			(layers "F.Cu" "F.Mask" "F.Paste")
			(net "M_E_CPU0_SB_PAR")
		)
		(pad "228" smd rect
			(at 2.050034 12.325096 270)
			(size 0.519938 1.4986)
			(layers "F.Cu" "F.Mask" "F.Paste")
			(net "GND")
		)
		(pad "229" smd rect
			(at 2.050034 13.17498 270)
			(size 0.519938 1.4986)
			(layers "F.Cu" "F.Mask" "F.Paste")
			(net "M_E_CPU0_SB_CS_N<1>")
		)
		(pad "230" smd rect
			(at 2.050034 14.025118 270)
			(size 0.519938 1.4986)
			(layers "F.Cu" "F.Mask" "F.Paste")
			(net "GND")
		)
		(pad "231" smd rect
			(at 2.050034 14.875002 270)
			(size 0.519938 1.4986)
			(layers "F.Cu" "F.Mask" "F.Paste")
			(net "TP_CHE_CPU0_DIMM1_FRU_5")
		)
		(pad "232" smd rect
			(at 2.050034 15.724886 270)
			(size 0.519938 1.4986)
			(layers "F.Cu" "F.Mask" "F.Paste")
			(net "TP_CHE_CPU0_DIMM1_FRU_6")
		)
		(pad "233" smd rect
			(at 2.050034 16.575024 270)
			(size 0.519938 1.4986)
			(layers "F.Cu" "F.Mask" "F.Paste")
			(net "GND")
		)
		(pad "234" smd rect
			(at 2.050034 17.424908 270)
			(size 0.519938 1.4986)
			(layers "F.Cu" "F.Mask" "F.Paste")
			(net "M_E_CPU0_SB_CB<6>")
		)
		(pad "235" smd rect
			(at 2.050034 18.275046 270)
			(size 0.519938 1.4986)
			(layers "F.Cu" "F.Mask" "F.Paste")
			(net "GND")
		)
		(pad "236" smd rect
			(at 2.050034 19.12493 270)
			(size 0.519938 1.4986)
			(layers "F.Cu" "F.Mask" "F.Paste")
			(net "M_E_CPU0_SB_CB<7>")
		)
		(pad "237" smd rect
			(at 2.050034 19.975068 270)
			(size 0.519938 1.4986)
			(layers "F.Cu" "F.Mask" "F.Paste")
			(net "GND")
		)
		(pad "238" smd rect
			(at 2.050034 20.824952 270)
			(size 0.519938 1.4986)
			(layers "F.Cu" "F.Mask" "F.Paste")
			(net "M_E_CPU0_SB_DQS_DN<4>")
		)
		(pad "239" smd rect
			(at 2.050034 21.67509 270)
			(size 0.519938 1.4986)
			(layers "F.Cu" "F.Mask" "F.Paste")
			(net "M_E_CPU0_SB_DQS_DP<4>")
		)
		(pad "240" smd rect
			(at 2.050034 22.524974 270)
			(size 0.519938 1.4986)
			(layers "F.Cu" "F.Mask" "F.Paste")
			(net "GND")
		)
		(pad "241" smd rect
			(at 2.050034 23.375112 270)
			(size 0.519938 1.4986)
			(layers "F.Cu" "F.Mask" "F.Paste")
			(net "M_E_CPU0_SB_CB<2>")
		)
		(pad "242" smd rect
			(at 2.050034 24.224996 270)
			(size 0.519938 1.4986)
			(layers "F.Cu" "F.Mask" "F.Paste")
			(net "GND")
		)
		(pad "243" smd rect
			(at 2.050034 25.07488 270)
			(size 0.519938 1.4986)
			(layers "F.Cu" "F.Mask" "F.Paste")
			(net "M_E_CPU0_SB_CB<3>")
		)
		(pad "244" smd rect
			(at 2.050034 25.925018 270)
			(size 0.519938 1.4986)
			(layers "F.Cu" "F.Mask" "F.Paste")
			(net "GND")
		)
		(pad "245" smd rect
			(at 2.050034 26.774902 270)
			(size 0.519938 1.4986)
			(layers "F.Cu" "F.Mask" "F.Paste")
			(net "M_E_CPU0_SB_DQ<2>")
		)
		(pad "246" smd rect
			(at 2.050034 27.62504 270)
			(size 0.519938 1.4986)
			(layers "F.Cu" "F.Mask" "F.Paste")
			(net "GND")
		)
		(pad "247" smd rect
			(at 2.050034 28.474924 270)
			(size 0.519938 1.4986)
			(layers "F.Cu" "F.Mask" "F.Paste")
			(net "M_E_CPU0_SB_DQ<3>")
		)
		(pad "248" smd rect
			(at 2.050034 29.325062 270)
			(size 0.519938 1.4986)
			(layers "F.Cu" "F.Mask" "F.Paste")
			(net "GND")
		)
		(pad "249" smd rect
			(at 2.050034 30.174946 270)
			(size 0.519938 1.4986)
			(layers "F.Cu" "F.Mask" "F.Paste")
			(net "M_E_CPU0_SB_DQS_DN<5>")
		)
		(pad "250" smd rect
			(at 2.050034 31.025084 270)
			(size 0.519938 1.4986)
			(layers "F.Cu" "F.Mask" "F.Paste")
			(net "M_E_CPU0_SB_DQS_DP<5>")
		)
		(pad "251" smd rect
			(at 2.050034 31.874968 270)
			(size 0.519938 1.4986)
			(layers "F.Cu" "F.Mask" "F.Paste")
			(net "GND")
		)
		(pad "252" smd rect
			(at 2.050034 32.725106 270)
			(size 0.519938 1.4986)
			(layers "F.Cu" "F.Mask" "F.Paste")
			(net "M_E_CPU0_SB_DQ<6>")
		)
		(pad "253" smd rect
			(at 2.050034 33.57499 270)
			(size 0.519938 1.4986)
			(layers "F.Cu" "F.Mask" "F.Paste")
			(net "GND")
		)
		(pad "254" smd rect
			(at 2.050034 34.425128 270)
			(size 0.519938 1.4986)
			(layers "F.Cu" "F.Mask" "F.Paste")
			(net "M_E_CPU0_SB_DQ<7>")
		)
		(pad "255" smd rect
			(at 2.050034 35.275012 270)
			(size 0.519938 1.4986)
			(layers "F.Cu" "F.Mask" "F.Paste")
			(net "GND")
		)
		(pad "256" smd rect
			(at 2.050034 36.124896 270)
			(size 0.519938 1.4986)
			(layers "F.Cu" "F.Mask" "F.Paste")
			(net "M_E_CPU0_SB_DQ<10>")
		)
		(pad "257" smd rect
			(at 2.050034 36.975034 270)
			(size 0.519938 1.4986)
			(layers "F.Cu" "F.Mask" "F.Paste")
			(net "GND")
		)
		(pad "258" smd rect
			(at 2.050034 37.824918 270)
			(size 0.519938 1.4986)
			(layers "F.Cu" "F.Mask" "F.Paste")
			(net "M_E_CPU0_SB_DQ<11>")
		)
		(pad "259" smd rect
			(at 2.050034 38.675056 270)
			(size 0.519938 1.4986)
			(layers "F.Cu" "F.Mask" "F.Paste")
			(net "GND")
		)
		(pad "260" smd rect
			(at 2.050034 39.52494 270)
			(size 0.519938 1.4986)
			(layers "F.Cu" "F.Mask" "F.Paste")
			(net "M_E_CPU0_SB_DQS_DN<6>")
		)
		(pad "261" smd rect
			(at 2.050034 40.375078 270)
			(size 0.519938 1.4986)
			(layers "F.Cu" "F.Mask" "F.Paste")
			(net "M_E_CPU0_SB_DQS_DP<6>")
		)
		(pad "262" smd rect
			(at 2.050034 41.224962 270)
			(size 0.519938 1.4986)
			(layers "F.Cu" "F.Mask" "F.Paste")
			(net "GND")
		)
		(pad "263" smd rect
			(at 2.050034 42.0751 270)
			(size 0.519938 1.4986)
			(layers "F.Cu" "F.Mask" "F.Paste")
			(net "M_E_CPU0_SB_DQ<14>")
		)
		(pad "264" smd rect
			(at 2.050034 42.924984 270)
			(size 0.519938 1.4986)
			(layers "F.Cu" "F.Mask" "F.Paste")
			(net "GND")
		)
		(pad "265" smd rect
			(at 2.050034 43.775122 270)
			(size 0.519938 1.4986)
			(layers "F.Cu" "F.Mask" "F.Paste")
			(net "M_E_CPU0_SB_DQ<15>")
		)
		(pad "266" smd rect
			(at 2.050034 44.625006 270)
			(size 0.519938 1.4986)
			(layers "F.Cu" "F.Mask" "F.Paste")
			(net "GND")
		)
		(pad "267" smd rect
			(at 2.050034 45.47489 270)
			(size 0.519938 1.4986)
			(layers "F.Cu" "F.Mask" "F.Paste")
			(net "M_E_CPU0_SB_DQ<18>")
		)
		(pad "268" smd rect
			(at 2.050034 46.325028 270)
			(size 0.519938 1.4986)
			(layers "F.Cu" "F.Mask" "F.Paste")
			(net "GND")
		)
		(pad "269" smd rect
			(at 2.050034 47.174912 270)
			(size 0.519938 1.4986)
			(layers "F.Cu" "F.Mask" "F.Paste")
			(net "M_E_CPU0_SB_DQ<19>")
		)
		(pad "270" smd rect
			(at 2.050034 48.02505 270)
			(size 0.519938 1.4986)
			(layers "F.Cu" "F.Mask" "F.Paste")
			(net "GND")
		)
		(pad "271" smd rect
			(at 2.050034 48.874934 270)
			(size 0.519938 1.4986)
			(layers "F.Cu" "F.Mask" "F.Paste")
			(net "M_E_CPU0_SB_DQS_DN<7>")
		)
		(pad "272" smd rect
			(at 2.050034 49.725072 270)
			(size 0.519938 1.4986)
			(layers "F.Cu" "F.Mask" "F.Paste")
			(net "M_E_CPU0_SB_DQS_DP<7>")
		)
		(pad "273" smd rect
			(at 2.050034 50.574956 270)
			(size 0.519938 1.4986)
			(layers "F.Cu" "F.Mask" "F.Paste")
			(net "GND")
		)
		(pad "274" smd rect
			(at 2.050034 51.425094 270)
			(size 0.519938 1.4986)
			(layers "F.Cu" "F.Mask" "F.Paste")
			(net "M_E_CPU0_SB_DQ<22>")
		)
		(pad "275" smd rect
			(at 2.050034 52.274978 270)
			(size 0.519938 1.4986)
			(layers "F.Cu" "F.Mask" "F.Paste")
			(net "GND")
		)
		(pad "276" smd rect
			(at 2.050034 53.125116 270)
			(size 0.519938 1.4986)
			(layers "F.Cu" "F.Mask" "F.Paste")
			(net "M_E_CPU0_SB_DQ<23>")
		)
		(pad "277" smd rect
			(at 2.050034 53.975 270)
			(size 0.519938 1.4986)
			(layers "F.Cu" "F.Mask" "F.Paste")
			(net "GND")
		)
		(pad "278" smd rect
			(at 2.050034 54.824884 270)
			(size 0.519938 1.4986)
			(layers "F.Cu" "F.Mask" "F.Paste")
			(net "M_E_CPU0_SB_DQ<26>")
		)
		(pad "279" smd rect
			(at 2.050034 55.675022 270)
			(size 0.519938 1.4986)
			(layers "F.Cu" "F.Mask" "F.Paste")
			(net "GND")
		)
		(pad "280" smd rect
			(at 2.050034 56.524906 270)
			(size 0.519938 1.4986)
			(layers "F.Cu" "F.Mask" "F.Paste")
			(net "M_E_CPU0_SB_DQ<27>")
		)
		(pad "281" smd rect
			(at 2.050034 57.375044 270)
			(size 0.519938 1.4986)
			(layers "F.Cu" "F.Mask" "F.Paste")
			(net "GND")
		)
		(pad "282" smd rect
			(at 2.050034 58.224928 270)
			(size 0.519938 1.4986)
			(layers "F.Cu" "F.Mask" "F.Paste")
			(net "M_E_CPU0_SB_DQS_DN<8>")
		)
		(pad "283" smd rect
			(at 2.050034 59.075066 270)
			(size 0.519938 1.4986)
			(layers "F.Cu" "F.Mask" "F.Paste")
			(net "M_E_CPU0_SB_DQS_DP<8>")
		)
		(pad "284" smd rect
			(at 2.050034 59.92495 270)
			(size 0.519938 1.4986)
			(layers "F.Cu" "F.Mask" "F.Paste")
			(net "GND")
		)
		(pad "285" smd rect
			(at 2.050034 60.775088 270)
			(size 0.519938 1.4986)
			(layers "F.Cu" "F.Mask" "F.Paste")
			(net "M_E_CPU0_SB_DQ<30>")
		)
		(pad "286" smd rect
			(at 2.050034 61.624972 270)
			(size 0.519938 1.4986)
			(layers "F.Cu" "F.Mask" "F.Paste")
			(net "GND")
		)
		(pad "287" smd rect
			(at 2.050034 62.47511 270)
			(size 0.519938 1.4986)
			(layers "F.Cu" "F.Mask" "F.Paste")
			(net "M_E_CPU0_SB_DQ<31>")
		)
		(pad "288" smd rect
			(at 2.050034 63.324994 270)
			(size 0.519938 1.4986)
			(layers "F.Cu" "F.Mask" "F.Paste")
			(net "GND")
		)
		(pad "G1" thru_hole oval
			(at 0 -68.97497)
			(size 2.8194 1.5748)
			(drill oval 2.4384 1.1938)
			(layers "*.Cu" "*.Mask")
			(remove_unused_layers no)
			(net "GND")
			(clearance 0.127)
			(thermal_gap 0.127)
		)
		(pad "G2" thru_hole oval
			(at 0 3.875024)
			(size 2.8194 1.5748)
			(drill oval 2.4384 1.1938)
			(layers "*.Cu" "*.Mask")
			(remove_unused_layers no)
			(net "GND")
			(clearance 0.127)
			(thermal_gap 0.127)
		)
		(pad "G3" thru_hole oval
			(at 0 68.97497)
			(size 2.8194 1.5748)
			(drill oval 2.4384 1.1938)
			(layers "*.Cu" "*.Mask")
			(remove_unused_layers no)
			(net "GND")
			(clearance 0.127)
			(thermal_gap 0.127)
		)
	)
)
